(kicad_pcb
	(version 20260206)
	(generator "pcbnew")
	(generator_version "10.0")
	(general
		(thickness 1.6)
		(legacy_teardrops no)
	)
	(paper "A4")
	(title_block
		(title "03242023_DA0F0TMBIJ0_F0T_Motherboard_J_brd_V01_OCP.brd")
		(comment 1 "Grand Teton / footprints 2592-2597 of 6105")
	)
	(layers
		(0 "F.Cu" signal "TOP")
		(4 "In1.Cu" signal "GND")
		(6 "In2.Cu" signal "IN1")
		(8 "In3.Cu" signal "GND1")
		(10 "In4.Cu" signal "IN2")
		(12 "In5.Cu" signal "GND2")
		(14 "In6.Cu" signal "IN3")
		(16 "In7.Cu" signal "GND3")
		(18 "In8.Cu" signal "VCC")
		(20 "In9.Cu" signal "VCC1")
		(22 "In10.Cu" signal "GND4")
		(24 "In11.Cu" signal "IN4")
		(26 "In12.Cu" signal "GND5")
		(28 "In13.Cu" signal "IN5")
		(30 "In14.Cu" signal "GND6")
		(32 "In15.Cu" signal "IN6")
		(34 "In16.Cu" signal "GND7")
		(2 "B.Cu" signal "BOTTOM")
		(9 "F.Adhes" user "F.Adhesive")
		(11 "B.Adhes" user "B.Adhesive")
		(13 "F.Paste" user "Package Geometry/Pastemask Top")
		(15 "B.Paste" user "Package Geometry/Pastemask Bottom")
		(5 "F.SilkS" user "Ref Des/Silkscreen Top")
		(7 "B.SilkS" user "Ref Des/Silkscreen Bottom")
		(1 "F.Mask" user "Board Geometry/Soldermask Top")
		(3 "B.Mask" user "Board Geometry/Soldermask Bottom")
		(17 "Dwgs.User" user "User.Drawings")
		(19 "Cmts.User" user "User.Comments")
		(21 "Eco1.User" user "User.Eco1")
		(23 "Eco2.User" user "User.Eco2")
		(25 "Edge.Cuts" user "Board Geometry/Outline")
		(27 "Margin" user)
		(31 "F.CrtYd" user "Package Geometry/Place Bound Top")
		(29 "B.CrtYd" user "Package Geometry/Place Bound Bottom")
		(35 "F.Fab" user "Ref Des/Assembly Top")
		(33 "B.Fab" user "Ref Des/Assembly Bottom")
	)
	(footprint ""
		(layer "F.Cu")
		(at 58.93308 -40.404034 180)
		(property "Reference" "R4066"
			(at 0 0 180)
			(layer "F.SilkS")
			(hide yes)
			(effects
				(font
					(size 1.27 1.27)
				)
			)
		)
		(property "Value" ""
			(at 0 0 180)
			(layer "F.Fab")
			(effects
				(font
					(size 1.27 1.27)
				)
			)
		)
		(duplicate_pad_numbers_are_jumpers no)
		(fp_line
			(start 0.7874 0.4064)
			(end -0.7874 0.4064)
			(stroke
				(width 0.1524)
				(type default)
			)
			(layer "F.SilkS")
		)
		(fp_line
			(start 0.7874 -0.4064)
			(end 0.7874 0.4064)
			(stroke
				(width 0.1524)
				(type default)
			)
			(layer "F.SilkS")
		)
		(fp_line
			(start -0.7874 0.4064)
			(end -0.7874 -0.4064)
			(stroke
				(width 0.1524)
				(type default)
			)
			(layer "F.SilkS")
		)
		(fp_line
			(start -0.7874 -0.4064)
			(end 0.7874 -0.4064)
			(stroke
				(width 0.1524)
				(type default)
			)
			(layer "F.SilkS")
		)
		(fp_line
			(start 0.67945 0.3048)
			(end 0.120396 0.3048)
			(stroke
				(width 0.1)
				(type default)
			)
			(layer "F.Fab")
		)
		(fp_line
			(start 0.67945 -0.3048)
			(end 0.67945 0.3048)
			(stroke
				(width 0.1)
				(type default)
			)
			(layer "F.Fab")
		)
		(fp_line
			(start 0.12065 -0.2794)
			(end 0.12065 -0.3048)
			(stroke
				(width 0.1)
				(type default)
			)
			(layer "F.Fab")
		)
		(fp_line
			(start 0.12065 -0.3048)
			(end 0.67945 -0.3048)
			(stroke
				(width 0.1)
				(type default)
			)
			(layer "F.Fab")
		)
		(fp_line
			(start 0.120396 0.3048)
			(end 0.120396 0.2794)
			(stroke
				(width 0.1)
				(type default)
			)
			(layer "F.Fab")
		)
		(fp_line
			(start 0.120396 0.2794)
			(end -0.12065 0.2794)
			(stroke
				(width 0.1)
				(type default)
			)
			(layer "F.Fab")
		)
		(fp_line
			(start -0.12065 0.3048)
			(end -0.67945 0.3048)
			(stroke
				(width 0.1)
				(type default)
			)
			(layer "F.Fab")
		)
		(fp_line
			(start -0.12065 0.2794)
			(end -0.12065 0.3048)
			(stroke
				(width 0.1)
				(type default)
			)
			(layer "F.Fab")
		)
		(fp_line
			(start -0.12065 -0.2794)
			(end 0.12065 -0.2794)
			(stroke
				(width 0.1)
				(type default)
			)
			(layer "F.Fab")
		)
		(fp_line
			(start -0.12065 -0.305054)
			(end -0.12065 -0.2794)
			(stroke
				(width 0.1)
				(type default)
			)
			(layer "F.Fab")
		)
		(fp_line
			(start -0.67945 0.3048)
			(end -0.67945 -0.305054)
			(stroke
				(width 0.1)
				(type default)
			)
			(layer "F.Fab")
		)
		(fp_line
			(start -0.67945 -0.305054)
			(end -0.12065 -0.305054)
			(stroke
				(width 0.1)
				(type default)
			)
			(layer "F.Fab")
		)
		(pad "1" smd circle
			(at -0.40005 0 180)
			(size 0 0)
			(layers "F.Cu" "F.Mask" "F.Paste")
			(net "P3V3_OCP_EN_2_R")
		)
		(pad "2" smd circle
			(at 0.40005 0 180)
			(size 0 0)
			(layers "F.Cu" "F.Mask" "F.Paste")
			(net "GND")
		)
	)
	(footprint ""
		(layer "F.Cu")
		(at 230.248206 -252.179836 180)
		(property "Reference" "R3335"
			(at 0 0 180)
			(layer "F.SilkS")
			(hide yes)
			(effects
				(font
					(size 1.27 1.27)
				)
			)
		)
		(property "Value" ""
			(at 0 0 180)
			(layer "F.Fab")
			(effects
				(font
					(size 1.27 1.27)
				)
			)
		)
		(duplicate_pad_numbers_are_jumpers no)
		(fp_line
			(start 0.7874 0.4064)
			(end -0.7874 0.4064)
			(stroke
				(width 0.1524)
				(type default)
			)
			(layer "F.SilkS")
		)
		(fp_line
			(start 0.7874 -0.4064)
			(end 0.7874 0.4064)
			(stroke
				(width 0.1524)
				(type default)
			)
			(layer "F.SilkS")
		)
		(fp_line
			(start -0.7874 0.4064)
			(end -0.7874 -0.4064)
			(stroke
				(width 0.1524)
				(type default)
			)
			(layer "F.SilkS")
		)
		(fp_line
			(start -0.7874 -0.4064)
			(end 0.7874 -0.4064)
			(stroke
				(width 0.1524)
				(type default)
			)
			(layer "F.SilkS")
		)
		(fp_line
			(start 0.67945 0.3048)
			(end 0.120396 0.3048)
			(stroke
				(width 0.1)
				(type default)
			)
			(layer "F.Fab")
		)
		(fp_line
			(start 0.67945 -0.3048)
			(end 0.67945 0.3048)
			(stroke
				(width 0.1)
				(type default)
			)
			(layer "F.Fab")
		)
		(fp_line
			(start 0.12065 -0.2794)
			(end 0.12065 -0.3048)
			(stroke
				(width 0.1)
				(type default)
			)
			(layer "F.Fab")
		)
		(fp_line
			(start 0.12065 -0.3048)
			(end 0.67945 -0.3048)
			(stroke
				(width 0.1)
				(type default)
			)
			(layer "F.Fab")
		)
		(fp_line
			(start 0.120396 0.3048)
			(end 0.120396 0.2794)
			(stroke
				(width 0.1)
				(type default)
			)
			(layer "F.Fab")
		)
		(fp_line
			(start 0.120396 0.2794)
			(end -0.12065 0.2794)
			(stroke
				(width 0.1)
				(type default)
			)
			(layer "F.Fab")
		)
		(fp_line
			(start -0.12065 0.3048)
			(end -0.67945 0.3048)
			(stroke
				(width 0.1)
				(type default)
			)
			(layer "F.Fab")
		)
		(fp_line
			(start -0.12065 0.2794)
			(end -0.12065 0.3048)
			(stroke
				(width 0.1)
				(type default)
			)
			(layer "F.Fab")
		)
		(fp_line
			(start -0.12065 -0.2794)
			(end 0.12065 -0.2794)
			(stroke
				(width 0.1)
				(type default)
			)
			(layer "F.Fab")
		)
		(fp_line
			(start -0.12065 -0.305054)
			(end -0.12065 -0.2794)
			(stroke
				(width 0.1)
				(type default)
			)
			(layer "F.Fab")
		)
		(fp_line
			(start -0.67945 0.3048)
			(end -0.67945 -0.305054)
			(stroke
				(width 0.1)
				(type default)
			)
			(layer "F.Fab")
		)
		(fp_line
			(start -0.67945 -0.305054)
			(end -0.12065 -0.305054)
			(stroke
				(width 0.1)
				(type default)
			)
			(layer "F.Fab")
		)
		(pad "1" smd circle
			(at -0.40005 0 180)
			(size 0 0)
			(layers "F.Cu" "F.Mask" "F.Paste")
			(net "CLK_100M_BMC_RC_DP_R")
		)
		(pad "2" smd circle
			(at 0.40005 0 180)
			(size 0 0)
			(layers "F.Cu" "F.Mask" "F.Paste")
			(net "CLK_100M_BMC_RC_DP")
		)
	)
	(footprint ""
		(layer "F.Cu")
		(at 48.501046 -358.129586 -90)
		(property "Reference" "PC1368"
			(at 0 0 270)
			(layer "F.SilkS")
			(hide yes)
			(effects
				(font
					(size 1.27 1.27)
				)
			)
		)
		(property "Value" ""
			(at 0 0 270)
			(layer "F.Fab")
			(effects
				(font
					(size 1.27 1.27)
				)
			)
		)
		(duplicate_pad_numbers_are_jumpers no)
		(fp_line
			(start -0.7874 0.4064)
			(end -0.7874 -0.4064)
			(stroke
				(width 0.1524)
				(type default)
			)
			(layer "F.SilkS")
		)
		(fp_line
			(start 0.7874 0.4064)
			(end -0.7874 0.4064)
			(stroke
				(width 0.1524)
				(type default)
			)
			(layer "F.SilkS")
		)
		(fp_line
			(start -0.7874 -0.4064)
			(end 0.7874 -0.4064)
			(stroke
				(width 0.1524)
				(type default)
			)
			(layer "F.SilkS")
		)
		(fp_line
			(start 0.7874 -0.4064)
			(end 0.7874 0.4064)
			(stroke
				(width 0.1524)
				(type default)
			)
			(layer "F.SilkS")
		)
		(fp_line
			(start -0.67945 0.3048)
			(end -0.67945 -0.305054)
			(stroke
				(width 0.1)
				(type default)
			)
			(layer "F.Fab")
		)
		(fp_line
			(start -0.12065 0.3048)
			(end -0.67945 0.3048)
			(stroke
				(width 0.1)
				(type default)
			)
			(layer "F.Fab")
		)
		(fp_line
			(start 0.120396 0.3048)
			(end 0.120396 0.2794)
			(stroke
				(width 0.1)
				(type default)
			)
			(layer "F.Fab")
		)
		(fp_line
			(start 0.67945 0.3048)
			(end 0.120396 0.3048)
			(stroke
				(width 0.1)
				(type default)
			)
			(layer "F.Fab")
		)
		(fp_line
			(start -0.12065 0.2794)
			(end -0.12065 0.3048)
			(stroke
				(width 0.1)
				(type default)
			)
			(layer "F.Fab")
		)
		(fp_line
			(start 0.120396 0.2794)
			(end -0.12065 0.2794)
			(stroke
				(width 0.1)
				(type default)
			)
			(layer "F.Fab")
		)
		(fp_line
			(start -0.12065 -0.2794)
			(end 0.12065 -0.2794)
			(stroke
				(width 0.1)
				(type default)
			)
			(layer "F.Fab")
		)
		(fp_line
			(start 0.12065 -0.2794)
			(end 0.12065 -0.3048)
			(stroke
				(width 0.1)
				(type default)
			)
			(layer "F.Fab")
		)
		(fp_line
			(start 0.12065 -0.3048)
			(end 0.67945 -0.3048)
			(stroke
				(width 0.1)
				(type default)
			)
			(layer "F.Fab")
		)
		(fp_line
			(start 0.67945 -0.3048)
			(end 0.67945 0.3048)
			(stroke
				(width 0.1)
				(type default)
			)
			(layer "F.Fab")
		)
		(fp_line
			(start -0.67945 -0.305054)
			(end -0.12065 -0.305054)
			(stroke
				(width 0.1)
				(type default)
			)
			(layer "F.Fab")
		)
		(fp_line
			(start -0.12065 -0.305054)
			(end -0.12065 -0.2794)
			(stroke
				(width 0.1)
				(type default)
			)
			(layer "F.Fab")
		)
		(pad "1" smd circle
			(at -0.40005 0 270)
			(size 0 0)
			(layers "F.Cu" "F.Mask" "F.Paste")
			(net "GND")
		)
		(pad "2" smd circle
			(at 0.40005 0 270)
			(size 0 0)
			(layers "F.Cu" "F.Mask" "F.Paste")
			(net "PVCCIN_CPU1_VREF")
		)
	)
	(footprint ""
		(layer "F.Cu")
		(at 158.901384 -44.632626 90)
		(property "Reference" "R4473"
			(at 0 0 90)
			(layer "F.SilkS")
			(hide yes)
			(effects
				(font
					(size 1.27 1.27)
				)
			)
		)
		(property "Value" ""
			(at 0 0 90)
			(layer "F.Fab")
			(effects
				(font
					(size 1.27 1.27)
				)
			)
		)
		(duplicate_pad_numbers_are_jumpers no)
		(fp_line
			(start -0.7874 -0.4064)
			(end 0.7874 -0.4064)
			(stroke
				(width 0.1524)
				(type default)
			)
			(layer "F.SilkS")
		)
		(fp_line
			(start -0.7874 0.4064)
			(end -0.7874 -0.4064)
			(stroke
				(width 0.1524)
				(type default)
			)
			(layer "F.SilkS")
		)
		(fp_line
			(start -0.12065 -0.305054)
			(end -0.12065 -0.2794)
			(stroke
				(width 0.1)
				(type default)
			)
			(layer "F.Fab")
		)
		(fp_line
			(start -0.67945 -0.305054)
			(end -0.12065 -0.305054)
			(stroke
				(width 0.1)
				(type default)
			)
			(layer "F.Fab")
		)
		(fp_line
			(start 0.67945 -0.3048)
			(end 0.67945 0.3048)
			(stroke
				(width 0.1)
				(type default)
			)
			(layer "F.Fab")
		)
		(fp_line
			(start 0.12065 -0.3048)
			(end 0.67945 -0.3048)
			(stroke
				(width 0.1)
				(type default)
			)
			(layer "F.Fab")
		)
		(fp_line
			(start 0.12065 -0.2794)
			(end 0.12065 -0.3048)
			(stroke
				(width 0.1)
				(type default)
			)
			(layer "F.Fab")
		)
		(fp_line
			(start -0.12065 -0.2794)
			(end 0.12065 -0.2794)
			(stroke
				(width 0.1)
				(type default)
			)
			(layer "F.Fab")
		)
		(fp_line
			(start 0.120396 0.2794)
			(end -0.12065 0.2794)
			(stroke
				(width 0.1)
				(type default)
			)
			(layer "F.Fab")
		)
		(fp_line
			(start -0.12065 0.2794)
			(end -0.12065 0.3048)
			(stroke
				(width 0.1)
				(type default)
			)
			(layer "F.Fab")
		)
		(fp_line
			(start 0.67945 0.3048)
			(end 0.120396 0.3048)
			(stroke
				(width 0.1)
				(type default)
			)
			(layer "F.Fab")
		)
		(fp_line
			(start 0.120396 0.3048)
			(end 0.120396 0.2794)
			(stroke
				(width 0.1)
				(type default)
			)
			(layer "F.Fab")
		)
		(fp_line
			(start -0.12065 0.3048)
			(end -0.67945 0.3048)
			(stroke
				(width 0.1)
				(type default)
			)
			(layer "F.Fab")
		)
		(fp_line
			(start -0.67945 0.3048)
			(end -0.67945 -0.305054)
			(stroke
				(width 0.1)
				(type default)
			)
			(layer "F.Fab")
		)
		(pad "1" smd rect
			(at -0.40005 0 270)
			(size 0.4572 0.508)
			(layers "F.Cu" "F.Mask" "F.Paste")
			(net "USB2_0_DP")
		)
		(pad "2" smd rect
			(at 0.40005 0 270)
			(size 0.4572 0.508)
			(layers "F.Cu" "F.Mask" "F.Paste")
			(net "USB2_HOST_PCH_0_DP")
		)
	)
	(footprint ""
		(layer "F.Cu")
		(at 312.443622 -45.202348 180)
		(property "Reference" "R698"
			(at 0 0 180)
			(layer "F.SilkS")
			(hide yes)
			(effects
				(font
					(size 1.27 1.27)
				)
			)
		)
		(property "Value" ""
			(at 0 0 180)
			(layer "F.Fab")
			(effects
				(font
					(size 1.27 1.27)
				)
			)
		)
		(duplicate_pad_numbers_are_jumpers no)
		(fp_line
			(start 0.7874 0.4064)
			(end -0.7874 0.4064)
			(stroke
				(width 0.1524)
				(type default)
			)
			(layer "F.SilkS")
		)
		(fp_line
			(start 0.7874 -0.4064)
			(end 0.7874 0.4064)
			(stroke
				(width 0.1524)
				(type default)
			)
			(layer "F.SilkS")
		)
		(fp_line
			(start -0.7874 0.4064)
			(end -0.7874 -0.4064)
			(stroke
				(width 0.1524)
				(type default)
			)
			(layer "F.SilkS")
		)
		(fp_line
			(start -0.7874 -0.4064)
			(end 0.7874 -0.4064)
			(stroke
				(width 0.1524)
				(type default)
			)
			(layer "F.SilkS")
		)
		(fp_line
			(start 0.67945 0.3048)
			(end 0.120396 0.3048)
			(stroke
				(width 0.1)
				(type default)
			)
			(layer "F.Fab")
		)
		(fp_line
			(start 0.67945 -0.3048)
			(end 0.67945 0.3048)
			(stroke
				(width 0.1)
				(type default)
			)
			(layer "F.Fab")
		)
		(fp_line
			(start 0.12065 -0.2794)
			(end 0.12065 -0.3048)
			(stroke
				(width 0.1)
				(type default)
			)
			(layer "F.Fab")
		)
		(fp_line
			(start 0.12065 -0.3048)
			(end 0.67945 -0.3048)
			(stroke
				(width 0.1)
				(type default)
			)
			(layer "F.Fab")
		)
		(fp_line
			(start 0.120396 0.3048)
			(end 0.120396 0.2794)
			(stroke
				(width 0.1)
				(type default)
			)
			(layer "F.Fab")
		)
		(fp_line
			(start 0.120396 0.2794)
			(end -0.12065 0.2794)
			(stroke
				(width 0.1)
				(type default)
			)
			(layer "F.Fab")
		)
		(fp_line
			(start -0.12065 0.3048)
			(end -0.67945 0.3048)
			(stroke
				(width 0.1)
				(type default)
			)
			(layer "F.Fab")
		)
		(fp_line
			(start -0.12065 0.2794)
			(end -0.12065 0.3048)
			(stroke
				(width 0.1)
				(type default)
			)
			(layer "F.Fab")
		)
		(fp_line
			(start -0.12065 -0.2794)
			(end 0.12065 -0.2794)
			(stroke
				(width 0.1)
				(type default)
			)
			(layer "F.Fab")
		)
		(fp_line
			(start -0.12065 -0.305054)
			(end -0.12065 -0.2794)
			(stroke
				(width 0.1)
				(type default)
			)
			(layer "F.Fab")
		)
		(fp_line
			(start -0.67945 0.3048)
			(end -0.67945 -0.305054)
			(stroke
				(width 0.1)
				(type default)
			)
			(layer "F.Fab")
		)
		(fp_line
			(start -0.67945 -0.305054)
			(end -0.12065 -0.305054)
			(stroke
				(width 0.1)
				(type default)
			)
			(layer "F.Fab")
		)
		(pad "1" smd circle
			(at -0.40005 0 180)
			(size 0 0)
			(layers "F.Cu" "F.Mask" "F.Paste")
			(net "FM_ADR_TRIGGER_R_N")
		)
		(pad "2" smd circle
			(at 0.40005 0 180)
			(size 0 0)
			(layers "F.Cu" "F.Mask" "F.Paste")
			(net "FM_ADR_TRIGGER_N")
		)
	)
	(footprint ""
		(layer "F.Cu")
		(at 67.994276 -79.078836)
		(property "Reference" "D82"
			(at -35.91941 34.331402 90)
			(unlocked yes)
			(layer "F.SilkS")
			(effects
				(font
					(size 0.635 0.4064)
					(thickness 0.1524)
				)
				(justify left)
			)
		)
		(property "Value" ""
			(at 0 0 0)
			(layer "F.Fab")
			(effects
				(font
					(size 1.27 1.27)
				)
			)
		)
		(duplicate_pad_numbers_are_jumpers no)
		(fp_line
			(start -0.90678 0.4826)
			(end -0.90678 -0.4699)
			(stroke
				(width 0.1524)
				(type default)
			)
			(layer "F.SilkS")
		)
		(fp_line
			(start -0.89408 -0.4826)
			(end 0.90678 -0.4826)
			(stroke
				(width 0.1524)
				(type default)
			)
			(layer "F.SilkS")
		)
		(fp_line
			(start -0.79248 -0.4826)
			(end 1.03378 -0.4826)
			(stroke
				(width 0.1524)
				(type default)
			)
			(layer "F.SilkS")
		)
		(fp_line
			(start -0.64008 -0.4826)
			(end 1.16078 -0.4826)
			(stroke
				(width 0.1524)
				(type default)
			)
			(layer "F.SilkS")
		)
		(fp_line
			(start 0.90678 -0.4826)
			(end 0.90678 0.4826)
			(stroke
				(width 0.1524)
				(type default)
			)
			(layer "F.SilkS")
		)
		(fp_line
			(start 0.90678 0.4826)
			(end -0.90678 0.4826)
			(stroke
				(width 0.1524)
				(type default)
			)
			(layer "F.SilkS")
		)
		(fp_line
			(start 1.03378 -0.4826)
			(end 1.03378 0.4826)
			(stroke
				(width 0.1524)
				(type default)
			)
			(layer "F.SilkS")
		)
		(fp_line
			(start 1.03378 0.4826)
			(end -0.79248 0.4826)
			(stroke
				(width 0.1524)
				(type default)
			)
			(layer "F.SilkS")
		)
		(fp_line
			(start 1.16078 -0.4826)
			(end 1.16078 0.4826)
			(stroke
				(width 0.1524)
				(type default)
			)
			(layer "F.SilkS")
		)
		(fp_line
			(start 1.16078 0.4826)
			(end -0.64008 0.4826)
			(stroke
				(width 0.1524)
				(type default)
			)
			(layer "F.SilkS")
		)
		(fp_line
			(start -0.499872 -0.249936)
			(end 0.499872 -0.249936)
			(stroke
				(width 0.1)
				(type default)
			)
			(layer "F.Fab")
		)
		(fp_line
			(start -0.499872 0.249936)
			(end -0.499872 -0.249936)
			(stroke
				(width 0.1)
				(type default)
			)
			(layer "F.Fab")
		)
		(fp_line
			(start 0.499872 -0.249936)
			(end 0.499872 0.249936)
			(stroke
				(width 0.1)
				(type default)
			)
			(layer "F.Fab")
		)
		(fp_line
			(start 0.499872 0.249936)
			(end -0.499872 0.249936)
			(stroke
				(width 0.1)
				(type default)
			)
			(layer "F.Fab")
		)
		(pad "A" smd rect
			(at -0.47498 0)
			(size 0.6096 0.7112)
			(layers "F.Cu" "F.Mask" "F.Paste")
			(net "LED_PWRGD_PVCCFA_EHV_CPU1")
		)
		(pad "C" smd rect
			(at 0.47498 0)
			(size 0.6096 0.7112)
			(layers "F.Cu" "F.Mask" "F.Paste")
			(net "LED_PWRGD_PVCCFA_EHV_CPU1_D")
		)
	)
)
